(kicad_pcb
	(version 20260206)
	(generator "pcbnew")
	(generator_version "10.0")
	(general
		(thickness 1.6)
		(legacy_teardrops no)
	)
	(paper "A4")
	(title_block
		(title "Wiwynn_Tioga_Pass_MB.brd")
		(comment 1 "Tioga Pass / footprints 1382-1388 of 4770")
	)
	(layers
		(0 "F.Cu" signal "TOP")
		(4 "In1.Cu" signal "L2GND")
		(6 "In2.Cu" signal "L3")
		(8 "In3.Cu" signal "L4GND")
		(10 "In4.Cu" signal "L5")
		(12 "In5.Cu" signal "L6GND")
		(14 "In6.Cu" signal "L7VCC")
		(16 "In7.Cu" signal "L8VCC")
		(18 "In8.Cu" signal "L9GND")
		(20 "In9.Cu" signal "L10")
		(22 "In10.Cu" signal "L11GND")
		(24 "In11.Cu" signal "L12")
		(26 "In12.Cu" signal "L13GND")
		(2 "B.Cu" signal "BOTTOM")
		(9 "F.Adhes" user "F.Adhesive")
		(11 "B.Adhes" user "B.Adhesive")
		(13 "F.Paste" user "Package Geometry/Pastemask Top")
		(15 "B.Paste" user "Package Geometry/Pastemask Bottom")
		(5 "F.SilkS" user "Ref Des/Silkscreen Top")
		(7 "B.SilkS" user "Ref Des/Silkscreen Bottom")
		(1 "F.Mask" user "Board Geometry/Soldermask Top")
		(3 "B.Mask" user "Board Geometry/Soldermask Bottom")
		(17 "Dwgs.User" user "User.Drawings")
		(19 "Cmts.User" user "User.Comments")
		(21 "Eco1.User" user "User.Eco1")
		(23 "Eco2.User" user "User.Eco2")
		(25 "Edge.Cuts" user "Board Geometry/Outline")
		(27 "Margin" user)
		(31 "F.CrtYd" user "Package Geometry/Place Bound Top")
		(29 "B.CrtYd" user "Package Geometry/Place Bound Bottom")
		(35 "F.Fab" user "Ref Des/Assembly Top")
		(33 "B.Fab" user "Ref Des/Assembly Bottom")
	)
	(footprint ""
		(layer "F.Cu")
		(at 438.833006 -43.568874 180)
		(property "Reference" "R25W47"
			(at 0 0 180)
			(layer "F.SilkS")
			(hide yes)
			(effects
				(font
					(size 1.27 1.27)
				)
			)
		)
		(property "Value" "*"
			(at 0.064008 -4.108196 180)
			(unlocked yes)
			(layer "F.Fab")
			(hide yes)
			(effects
				(font
					(size 1.27 1.016)
					(thickness 0.1524)
				)
			)
		)
		(property "Device Type" "120R2F-GP_RCL_GP-120R2F-GP,64.A"
			(at 0.064008 -5.632196 180)
			(unlocked yes)
			(layer "F.Fab")
			(hide yes)
			(effects
				(font
					(size 1.27 1.016)
					(thickness 0.1524)
				)
			)
		)
		(duplicate_pad_numbers_are_jumpers no)
		(fp_line
			(start 0.508 -0.9398)
			(end -0.508 -0.9398)
			(stroke
				(width 0.1524)
				(type default)
			)
			(layer "F.SilkS")
		)
		(fp_line
			(start -0.508 -0.9398)
			(end -0.508 0.9398)
			(stroke
				(width 0.1524)
				(type default)
			)
			(layer "F.SilkS")
		)
		(fp_rect
			(start -0.508 0.9398)
			(end 0.508 -0.9398)
			(stroke
				(width 0)
				(type default)
			)
			(fill no)
			(layer "F.CrtYd")
		)
		(fp_rect
			(start -0.508 0.9398)
			(end 0.508 -0.9398)
			(stroke
				(width 0)
				(type default)
			)
			(fill no)
			(layer "F.Fab")
		)
		(pad "1" smd custom
			(at 0 -0.4445 180)
			(size 0.1397 0.1397)
			(layers "F.Cu" "F.Mask" "F.Paste")
			(net "BMC_M_A9")
			(options
				(clearance outline)
				(anchor circle)
			)
			(primitives
				(gr_poly
					(pts
						(arc
							(start -0.1778 -0.2794)
							(mid -0.249642 -0.249642)
							(end -0.2794 -0.1778)
						)
						(arc
							(start -0.2794 0.1778)
							(mid -0.249642 0.249642)
							(end -0.1778 0.2794)
						)
						(arc
							(start 0.1778 0.2794)
							(mid 0.249642 0.249642)
							(end 0.2794 0.1778)
						)
						(arc
							(start 0.2794 -0.1778)
							(mid 0.249642 -0.249642)
							(end 0.1778 -0.2794)
						)
					)
					(width 0)
					(fill yes)
				)
			)
		)
		(pad "2" smd custom
			(at 0 0.4445 180)
			(size 0.1397 0.1397)
			(layers "F.Cu" "F.Mask" "F.Paste")
			(net "P1V2_AUX_BMC")
			(options
				(clearance outline)
				(anchor circle)
			)
			(primitives
				(gr_poly
					(pts
						(arc
							(start -0.1778 -0.2794)
							(mid -0.249642 -0.249642)
							(end -0.2794 -0.1778)
						)
						(arc
							(start -0.2794 0.1778)
							(mid -0.249642 0.249642)
							(end -0.1778 0.2794)
						)
						(arc
							(start 0.1778 0.2794)
							(mid 0.249642 0.249642)
							(end 0.2794 0.1778)
						)
						(arc
							(start 0.2794 -0.1778)
							(mid 0.249642 -0.249642)
							(end 0.1778 -0.2794)
						)
					)
					(width 0)
					(fill yes)
				)
			)
		)
	)
	(footprint ""
		(layer "F.Cu")
		(at 198.370444 -102.053136 90)
		(property "Reference" "C4C10"
			(at 0 0 90)
			(layer "F.SilkS")
			(hide yes)
			(effects
				(font
					(size 1.27 1.27)
				)
			)
		)
		(property "Value" ""
			(at 0 0 90)
			(layer "F.Fab")
			(effects
				(font
					(size 1.27 1.27)
				)
			)
		)
		(duplicate_pad_numbers_are_jumpers no)
		(fp_rect
			(start 0.3048 0.9906)
			(end -0.3048 -0.1016)
			(stroke
				(width 0)
				(type default)
			)
			(fill no)
			(layer "F.CrtYd")
		)
		(fp_line
			(start 0.3048 -0.1016)
			(end -0.3048 -0.1016)
			(stroke
				(width 0.1)
				(type default)
			)
			(layer "F.Fab")
		)
		(fp_line
			(start -0.3048 -0.1016)
			(end -0.3048 0.9906)
			(stroke
				(width 0.1)
				(type default)
			)
			(layer "F.Fab")
		)
		(fp_line
			(start 0.3048 0.9906)
			(end 0.3048 -0.1016)
			(stroke
				(width 0.1)
				(type default)
			)
			(layer "F.Fab")
		)
		(fp_line
			(start -0.3048 0.9906)
			(end 0.3048 0.9906)
			(stroke
				(width 0.1)
				(type default)
			)
			(layer "F.Fab")
		)
		(pad "1" smd rect
			(at 0 0 90)
			(size 0.508 0.508)
			(layers "F.Cu" "F.Mask" "F.Paste")
			(net "VR_FET_SW_P12V_STBY_PVCCIN_CPU0")
		)
		(pad "2" smd rect
			(at 0 0.889 90)
			(size 0.508 0.508)
			(layers "F.Cu" "F.Mask" "F.Paste")
			(net "GND")
		)
		(zone
			(layer "F.Cu")
			(hatch none 0.5)
			(connect_pads
				(clearance 0)
			)
			(min_thickness 0.25)
			(keepout
				(tracks allowed)
				(vias not_allowed)
				(pads allowed)
				(copperpour not_allowed)
				(footprints allowed)
			)
			(placement
				(enabled no)
				(sheetname "")
			)
			(fill
				(thermal_gap 0.5)
				(thermal_bridge_width 0.5)
				(island_removal_mode 0)
			)
			(polygon
				(pts
					(xy 199.005444 -102.307136) (xy 198.624444 -102.307136) (xy 198.624444 -101.799136) (xy 199.005444 -101.799136)
				)
			)
		)
		(zone
			(layer "F.Cu")
			(hatch none 0.5)
			(connect_pads
				(clearance 0)
			)
			(min_thickness 0.25)
			(keepout
				(tracks not_allowed)
				(vias allowed)
				(pads allowed)
				(copperpour not_allowed)
				(footprints allowed)
			)
			(placement
				(enabled no)
				(sheetname "")
			)
			(fill
				(thermal_gap 0.5)
				(thermal_bridge_width 0.5)
				(island_removal_mode 0)
			)
			(polygon
				(pts
					(xy 199.005444 -102.307136) (xy 198.624444 -102.307136) (xy 198.624444 -101.799136) (xy 199.005444 -101.799136)
				)
			)
		)
	)
	(footprint ""
		(layer "F.Cu")
		(at 6.388608 -2.16281 -90)
		(property "Reference" "RF19"
			(at -0.8382 -0.67818 270)
			(unlocked yes)
			(layer "F.SilkS")
			(effects
				(font
					(size 0.4064 0.254)
					(thickness 0.1524)
				)
				(justify left)
			)
		)
		(property "Value" ""
			(at 0 0 270)
			(layer "F.Fab")
			(effects
				(font
					(size 1.27 1.27)
				)
			)
		)
		(duplicate_pad_numbers_are_jumpers no)
		(fp_poly
			(pts
				(xy -0.2794 -0.1016) (xy 0.2794 -0.1016) (xy 0.2794 0.9906) (xy -0.2794 0.9906)
			)
			(stroke
				(width 0)
				(type default)
			)
			(fill no)
			(layer "F.CrtYd")
		)
		(fp_line
			(start -0.2794 0.9906)
			(end 0.2794 0.9906)
			(stroke
				(width 0.1)
				(type default)
			)
			(layer "F.Fab")
		)
		(fp_line
			(start 0.2794 0.9906)
			(end 0.2794 -0.1016)
			(stroke
				(width 0.1)
				(type default)
			)
			(layer "F.Fab")
		)
		(fp_line
			(start -0.2794 -0.1016)
			(end -0.2794 0.9906)
			(stroke
				(width 0.1)
				(type default)
			)
			(layer "F.Fab")
		)
		(fp_line
			(start 0.2794 -0.1016)
			(end -0.2794 -0.1016)
			(stroke
				(width 0.1)
				(type default)
			)
			(layer "F.Fab")
		)
		(pad "1" smd rect
			(at 0 0 270)
			(size 0.508 0.508)
			(layers "F.Cu" "F.Mask" "F.Paste")
			(net "VR_PVDDQ_GHJ_AIREF1")
		)
		(pad "2" smd rect
			(at 0 0.889 270)
			(size 0.508 0.508)
			(layers "F.Cu" "F.Mask" "F.Paste")
			(net "ISENSE_PVDDQ_GHJ_PH1_IMON")
		)
		(zone
			(layer "F.Cu")
			(hatch none 0.5)
			(connect_pads
				(clearance 0)
			)
			(min_thickness 0.25)
			(keepout
				(tracks not_allowed)
				(vias allowed)
				(pads allowed)
				(copperpour not_allowed)
				(footprints allowed)
			)
			(placement
				(enabled no)
				(sheetname "")
			)
			(fill
				(thermal_gap 0.5)
				(thermal_bridge_width 0.5)
				(island_removal_mode 0)
			)
			(polygon
				(pts
					(xy 5.753608 -2.41681) (xy 5.753608 -1.90881) (xy 6.134608 -1.90881) (xy 6.134608 -2.41681)
				)
			)
		)
		(zone
			(layer "F.Cu")
			(hatch none 0.5)
			(connect_pads
				(clearance 0)
			)
			(min_thickness 0.25)
			(keepout
				(tracks allowed)
				(vias not_allowed)
				(pads allowed)
				(copperpour not_allowed)
				(footprints allowed)
			)
			(placement
				(enabled no)
				(sheetname "")
			)
			(fill
				(thermal_gap 0.5)
				(thermal_bridge_width 0.5)
				(island_removal_mode 0)
			)
			(polygon
				(pts
					(xy 6.134608 -2.41681) (xy 6.134608 -1.90881) (xy 5.753608 -1.90881) (xy 5.753608 -2.41681)
				)
			)
		)
	)
	(footprint ""
		(layer "F.Cu")
		(at 345.6178 -23.4823)
		(property "Reference" "R7F15"
			(at 0 0 0)
			(layer "F.SilkS")
			(hide yes)
			(effects
				(font
					(size 1.27 1.27)
				)
			)
		)
		(property "Value" ""
			(at 0 0 0)
			(layer "F.Fab")
			(effects
				(font
					(size 1.27 1.27)
				)
			)
		)
		(duplicate_pad_numbers_are_jumpers no)
		(fp_rect
			(start -0.2794 0.9906)
			(end 0.2794 -0.1016)
			(stroke
				(width 0)
				(type default)
			)
			(fill no)
			(layer "F.CrtYd")
		)
		(fp_line
			(start -0.2794 -0.1016)
			(end -0.2794 0.9906)
			(stroke
				(width 0.1)
				(type default)
			)
			(layer "F.Fab")
		)
		(fp_line
			(start -0.2794 0.9906)
			(end 0.2794 0.9906)
			(stroke
				(width 0.1)
				(type default)
			)
			(layer "F.Fab")
		)
		(fp_line
			(start 0.2794 -0.1016)
			(end -0.2794 -0.1016)
			(stroke
				(width 0.1)
				(type default)
			)
			(layer "F.Fab")
		)
		(fp_line
			(start 0.2794 0.9906)
			(end 0.2794 -0.1016)
			(stroke
				(width 0.1)
				(type default)
			)
			(layer "F.Fab")
		)
		(pad "1" smd rect
			(at 0 0)
			(size 0.508 0.508)
			(layers "F.Cu" "F.Mask" "F.Paste")
			(net "VR_PVPP_ABC_ISET")
		)
		(pad "2" smd rect
			(at 0 0.889)
			(size 0.508 0.508)
			(layers "F.Cu" "F.Mask" "F.Paste")
			(net "AGND_PVPP_ABC")
		)
		(zone
			(layer "F.Cu")
			(hatch none 0.5)
			(connect_pads
				(clearance 0)
			)
			(min_thickness 0.25)
			(keepout
				(tracks allowed)
				(vias not_allowed)
				(pads allowed)
				(copperpour not_allowed)
				(footprints allowed)
			)
			(placement
				(enabled no)
				(sheetname "")
			)
			(fill
				(thermal_gap 0.5)
				(thermal_bridge_width 0.5)
				(island_removal_mode 0)
			)
			(polygon
				(pts
					(xy 345.3638 -22.8473) (xy 345.8718 -22.8473) (xy 345.8718 -23.2283) (xy 345.3638 -23.2283)
				)
			)
		)
		(zone
			(layer "F.Cu")
			(hatch none 0.5)
			(connect_pads
				(clearance 0)
			)
			(min_thickness 0.25)
			(keepout
				(tracks not_allowed)
				(vias allowed)
				(pads allowed)
				(copperpour not_allowed)
				(footprints allowed)
			)
			(placement
				(enabled no)
				(sheetname "")
			)
			(fill
				(thermal_gap 0.5)
				(thermal_bridge_width 0.5)
				(island_removal_mode 0)
			)
			(polygon
				(pts
					(xy 345.3638 -22.8473) (xy 345.8718 -22.8473) (xy 345.8718 -23.2283) (xy 345.3638 -23.2283)
				)
			)
		)
	)
	(footprint ""
		(layer "F.Cu")
		(at 476.6691 -141.6177 180)
		(property "Reference" "C9A3"
			(at 0 0 180)
			(layer "F.SilkS")
			(hide yes)
			(effects
				(font
					(size 1.27 1.27)
				)
			)
		)
		(property "Value" ""
			(at 0 0 180)
			(layer "F.Fab")
			(effects
				(font
					(size 1.27 1.27)
				)
			)
		)
		(duplicate_pad_numbers_are_jumpers no)
		(fp_poly
			(pts
				(xy 0.3048 -0.1016) (xy 0.3048 0.9906) (xy -0.3048 0.9906) (xy -0.3048 -0.1016)
			)
			(stroke
				(width 0)
				(type default)
			)
			(fill no)
			(layer "F.CrtYd")
		)
		(fp_line
			(start 0.3048 0.9906)
			(end 0.3048 -0.1016)
			(stroke
				(width 0.1)
				(type default)
			)
			(layer "F.Fab")
		)
		(fp_line
			(start 0.3048 -0.1016)
			(end -0.3048 -0.1016)
			(stroke
				(width 0.1)
				(type default)
			)
			(layer "F.Fab")
		)
		(fp_line
			(start -0.3048 0.9906)
			(end 0.3048 0.9906)
			(stroke
				(width 0.1)
				(type default)
			)
			(layer "F.Fab")
		)
		(fp_line
			(start -0.3048 -0.1016)
			(end -0.3048 0.9906)
			(stroke
				(width 0.1)
				(type default)
			)
			(layer "F.Fab")
		)
		(pad "1" smd rect
			(at 0 0 180)
			(size 0.508 0.508)
			(layers "F.Cu" "F.Mask" "F.Paste")
			(net "P3V3_STBY")
		)
		(pad "2" smd rect
			(at 0 0.889 180)
			(size 0.508 0.508)
			(layers "F.Cu" "F.Mask" "F.Paste")
			(net "GND")
		)
		(zone
			(layer "F.Cu")
			(hatch none 0.5)
			(connect_pads
				(clearance 0)
			)
			(min_thickness 0.25)
			(keepout
				(tracks not_allowed)
				(vias allowed)
				(pads allowed)
				(copperpour not_allowed)
				(footprints allowed)
			)
			(placement
				(enabled no)
				(sheetname "")
			)
			(fill
				(thermal_gap 0.5)
				(thermal_bridge_width 0.5)
				(island_removal_mode 0)
			)
			(polygon
				(pts
					(xy 476.9231 -142.2527) (xy 476.4151 -142.2527) (xy 476.4151 -141.8717) (xy 476.9231 -141.8717)
				)
			)
		)
		(zone
			(layer "F.Cu")
			(hatch none 0.5)
			(connect_pads
				(clearance 0)
			)
			(min_thickness 0.25)
			(keepout
				(tracks allowed)
				(vias not_allowed)
				(pads allowed)
				(copperpour not_allowed)
				(footprints allowed)
			)
			(placement
				(enabled no)
				(sheetname "")
			)
			(fill
				(thermal_gap 0.5)
				(thermal_bridge_width 0.5)
				(island_removal_mode 0)
			)
			(polygon
				(pts
					(xy 476.9231 -141.8717) (xy 476.4151 -141.8717) (xy 476.4151 -142.2527) (xy 476.9231 -142.2527)
				)
			)
		)
	)
	(footprint ""
		(layer "F.Cu")
		(at 177.165 -80.137 90)
		(property "Reference" "R4D20"
			(at 0 0 90)
			(layer "F.SilkS")
			(hide yes)
			(effects
				(font
					(size 1.27 1.27)
				)
			)
		)
		(property "Value" ""
			(at 0 0 90)
			(layer "F.Fab")
			(effects
				(font
					(size 1.27 1.27)
				)
			)
		)
		(duplicate_pad_numbers_are_jumpers no)
		(fp_poly
			(pts
				(xy -0.2794 -0.1016) (xy 0.2794 -0.1016) (xy 0.2794 0.9906) (xy -0.2794 0.9906)
			)
			(stroke
				(width 0)
				(type default)
			)
			(fill no)
			(layer "F.CrtYd")
		)
		(fp_line
			(start 0.2794 -0.1016)
			(end -0.2794 -0.1016)
			(stroke
				(width 0.1)
				(type default)
			)
			(layer "F.Fab")
		)
		(fp_line
			(start -0.2794 -0.1016)
			(end -0.2794 0.9906)
			(stroke
				(width 0.1)
				(type default)
			)
			(layer "F.Fab")
		)
		(fp_line
			(start 0.2794 0.9906)
			(end 0.2794 -0.1016)
			(stroke
				(width 0.1)
				(type default)
			)
			(layer "F.Fab")
		)
		(fp_line
			(start -0.2794 0.9906)
			(end 0.2794 0.9906)
			(stroke
				(width 0.1)
				(type default)
			)
			(layer "F.Fab")
		)
		(pad "1" smd rect
			(at 0 0 90)
			(size 0.508 0.508)
			(layers "F.Cu" "F.Mask" "F.Paste")
			(net "CLK_100M_CPU0_BCLK1_R_DN")
		)
		(pad "2" smd rect
			(at 0 0.889 90)
			(size 0.508 0.508)
			(layers "F.Cu" "F.Mask" "F.Paste")
			(net "CLK_100M_CPU0_BCLK1_DN")
		)
		(zone
			(layer "F.Cu")
			(hatch none 0.5)
			(connect_pads
				(clearance 0)
			)
			(min_thickness 0.25)
			(keepout
				(tracks allowed)
				(vias not_allowed)
				(pads allowed)
				(copperpour not_allowed)
				(footprints allowed)
			)
			(placement
				(enabled no)
				(sheetname "")
			)
			(fill
				(thermal_gap 0.5)
				(thermal_bridge_width 0.5)
				(island_removal_mode 0)
			)
			(polygon
				(pts
					(xy 177.419 -79.883) (xy 177.419 -80.391) (xy 177.8 -80.391) (xy 177.8 -79.883)
				)
			)
		)
		(zone
			(layer "F.Cu")
			(hatch none 0.5)
			(connect_pads
				(clearance 0)
			)
			(min_thickness 0.25)
			(keepout
				(tracks not_allowed)
				(vias allowed)
				(pads allowed)
				(copperpour not_allowed)
				(footprints allowed)
			)
			(placement
				(enabled no)
				(sheetname "")
			)
			(fill
				(thermal_gap 0.5)
				(thermal_bridge_width 0.5)
				(island_removal_mode 0)
			)
			(polygon
				(pts
					(xy 177.8 -79.883) (xy 177.8 -80.391) (xy 177.419 -80.391) (xy 177.419 -79.883)
				)
			)
		)
	)
	(footprint ""
		(layer "F.Cu")
		(at 481.6983 -137.033 90)
		(property "Reference" "R9A20"
			(at 0 0 90)
			(layer "F.SilkS")
			(hide yes)
			(effects
				(font
					(size 1.27 1.27)
				)
			)
		)
		(property "Value" ""
			(at 0 0 90)
			(layer "F.Fab")
			(effects
				(font
					(size 1.27 1.27)
				)
			)
		)
		(duplicate_pad_numbers_are_jumpers no)
		(fp_poly
			(pts
				(xy -0.2794 -0.1016) (xy 0.2794 -0.1016) (xy 0.2794 0.9906) (xy -0.2794 0.9906)
			)
			(stroke
				(width 0)
				(type default)
			)
			(fill no)
			(layer "F.CrtYd")
		)
		(fp_line
			(start 0.2794 -0.1016)
			(end -0.2794 -0.1016)
			(stroke
				(width 0.1)
				(type default)
			)
			(layer "F.Fab")
		)
		(fp_line
			(start -0.2794 -0.1016)
			(end -0.2794 0.9906)
			(stroke
				(width 0.1)
				(type default)
			)
			(layer "F.Fab")
		)
		(fp_line
			(start 0.2794 0.9906)
			(end 0.2794 -0.1016)
			(stroke
				(width 0.1)
				(type default)
			)
			(layer "F.Fab")
		)
		(fp_line
			(start -0.2794 0.9906)
			(end 0.2794 0.9906)
			(stroke
				(width 0.1)
				(type default)
			)
			(layer "F.Fab")
		)
		(pad "1" smd rect
			(at 0 0 90)
			(size 0.508 0.508)
			(layers "F.Cu" "F.Mask" "F.Paste")
			(net "FM_PWR_LED_A")
		)
		(pad "2" smd rect
			(at 0 0.889 90)
			(size 0.508 0.508)
			(layers "F.Cu" "F.Mask" "F.Paste")
			(net "P3V3_STBY")
		)
		(zone
			(layer "F.Cu")
			(hatch none 0.5)
			(connect_pads
				(clearance 0)
			)
			(min_thickness 0.25)
			(keepout
				(tracks allowed)
				(vias not_allowed)
				(pads allowed)
				(copperpour not_allowed)
				(footprints allowed)
			)
			(placement
				(enabled no)
				(sheetname "")
			)
			(fill
				(thermal_gap 0.5)
				(thermal_bridge_width 0.5)
				(island_removal_mode 0)
			)
			(polygon
				(pts
					(xy 481.9523 -136.779) (xy 481.9523 -137.287) (xy 482.3333 -137.287) (xy 482.3333 -136.779)
				)
			)
		)
		(zone
			(layer "F.Cu")
			(hatch none 0.5)
			(connect_pads
				(clearance 0)
			)
			(min_thickness 0.25)
			(keepout
				(tracks not_allowed)
				(vias allowed)
				(pads allowed)
				(copperpour not_allowed)
				(footprints allowed)
			)
			(placement
				(enabled no)
				(sheetname "")
			)
			(fill
				(thermal_gap 0.5)
				(thermal_bridge_width 0.5)
				(island_removal_mode 0)
			)
			(polygon
				(pts
					(xy 482.3333 -136.779) (xy 482.3333 -137.287) (xy 481.9523 -137.287) (xy 481.9523 -136.779)
				)
			)
		)
	)
)
